# T6G (Grand Teton) — schematic netlist excerpt (pin names and nets, part order shuffled) for the footprints in the layout excerpt that follows; sources: Cadence DE-HDL packaged netlist, KiCad conversion of 04192023_DAF0TMB3IC0_F0TG_MB_C_brd_V02_OCP.brd

R858  Q_RES  0 5% EMPTY  pkg 0603LF  page 345 : A = P0V9_CPU1_RT_2D ; B = P0V9_CPU1_RT2_2A_2D
C6543  Q_CAP_DIFFBUS  DIFF BUS_0.22UF 6.3V 20% X6S  pkg C0201  page 286 : \1\ = P5E_CPU0_P1_TX_BUF_C_DP<5> ; \2\ = P5E_CPU0_P1_TX_BUF_DP<5>
R1230  Q_RES  2K 1% CHIP  pkg 0402LF  page 258 : A = MAX11617_2_VREF ; B = MAX11617_2_VREF_R

(kicad_pcb
	(version 20260206)
	(generator "pcbnew")
	(generator_version "10.0")
	(general
		(thickness 1.6)
		(legacy_teardrops no)
	)
	(paper "A4")
	(title_block
		(title "04192023_DAF0TMB3IC0_F0TG_MB_C_brd_V02_OCP.brd")
		(comment 1 "Grand Teton / footprints 5215-5217 of 8354")
	)
	(layers
		(0 "F.Cu" signal "TOP")
		(4 "In1.Cu" signal "GND")
		(6 "In2.Cu" signal "IN1")
		(8 "In3.Cu" signal "GND1")
		(10 "In4.Cu" signal "IN2")
		(12 "In5.Cu" signal "GND2")
		(14 "In6.Cu" signal "IN3")
		(16 "In7.Cu" signal "GND3")
		(18 "In8.Cu" signal "VCC")
		(20 "In9.Cu" signal "VCC1")
		(22 "In10.Cu" signal "GND4")
		(24 "In11.Cu" signal "IN4")
		(26 "In12.Cu" signal "GND5")
		(28 "In13.Cu" signal "IN5")
		(30 "In14.Cu" signal "GND6")
		(32 "In15.Cu" signal "IN6")
		(34 "In16.Cu" signal "GND7")
		(2 "B.Cu" signal "BOTTOM")
		(9 "F.Adhes" user "F.Adhesive")
		(11 "B.Adhes" user "B.Adhesive")
		(13 "F.Paste" user "Package Geometry/Pastemask Top")
		(15 "B.Paste" user "Package Geometry/Pastemask Bottom")
		(5 "F.SilkS" user "Ref Des/Silkscreen Top")
		(7 "B.SilkS" user "Ref Des/Silkscreen Bottom")
		(1 "F.Mask" user "Board Geometry/Soldermask Top")
		(3 "B.Mask" user "Board Geometry/Soldermask Bottom")
		(17 "Dwgs.User" user "User.Drawings")
		(19 "Cmts.User" user "User.Comments")
		(21 "Eco1.User" user "User.Eco1")
		(23 "Eco2.User" user "User.Eco2")
		(25 "Edge.Cuts" user "Board Geometry/Outline")
		(27 "Margin" user)
		(31 "F.CrtYd" user "Package Geometry/Place Bound Top")
		(29 "B.CrtYd" user "Package Geometry/Place Bound Bottom")
		(35 "F.Fab" user "Ref Des/Assembly Top")
		(33 "B.Fab" user "Ref Des/Assembly Bottom")
	)
	(footprint ""
		(layer "B.Cu")
		(at 139.516358 -393.242546 180)
		(property "Reference" "R858"
			(at 0 0 0)
			(layer "B.SilkS")
			(hide yes)
			(effects
				(font
					(size 1.27 1.27)
				)
				(justify mirror)
			)
		)
		(property "Value" ""
			(at 0 0 0)
			(layer "B.Fab")
			(effects
				(font
					(size 1.27 1.27)
				)
				(justify mirror)
			)
		)
		(duplicate_pad_numbers_are_jumpers no)
		(fp_line
			(start 1.2954 0.5842)
			(end 1.2954 -0.5842)
			(stroke
				(width 0.1524)
				(type default)
			)
			(layer "B.SilkS")
		)
		(fp_line
			(start 1.2954 -0.5842)
			(end -1.2954 -0.5842)
			(stroke
				(width 0.1524)
				(type default)
			)
			(layer "B.SilkS")
		)
		(fp_line
			(start -1.2954 0.5842)
			(end 1.2954 0.5842)
			(stroke
				(width 0.1524)
				(type default)
			)
			(layer "B.SilkS")
		)
		(fp_line
			(start -1.2954 -0.5842)
			(end -1.2954 0.5842)
			(stroke
				(width 0.1524)
				(type default)
			)
			(layer "B.SilkS")
		)
		(fp_line
			(start 1.1938 0.4064)
			(end 1.1938 -0.406654)
			(stroke
				(width 0.1)
				(type default)
			)
			(layer "B.Fab")
		)
		(fp_line
			(start 1.1938 -0.406654)
			(end 0.8636 -0.406654)
			(stroke
				(width 0.1)
				(type default)
			)
			(layer "B.Fab")
		)
		(fp_line
			(start 0.8636 0.4572)
			(end 0.8636 0.4318)
			(stroke
				(width 0.1)
				(type default)
			)
			(layer "B.Fab")
		)
		(fp_line
			(start 0.8636 0.4318)
			(end 0.8636 0.4064)
			(stroke
				(width 0.1)
				(type default)
			)
			(layer "B.Fab")
		)
		(fp_line
			(start 0.8636 0.4064)
			(end 1.1938 0.4064)
			(stroke
				(width 0.1)
				(type default)
			)
			(layer "B.Fab")
		)
		(fp_line
			(start 0.8636 -0.406654)
			(end 0.8636 -0.4572)
			(stroke
				(width 0.1)
				(type default)
			)
			(layer "B.Fab")
		)
		(fp_line
			(start 0.8636 -0.4572)
			(end -0.8636 -0.4572)
			(stroke
				(width 0.1)
				(type default)
			)
			(layer "B.Fab")
		)
		(fp_line
			(start -0.8636 0.4572)
			(end 0.8636 0.4572)
			(stroke
				(width 0.1)
				(type default)
			)
			(layer "B.Fab")
		)
		(fp_line
			(start -0.8636 0.4064)
			(end -0.8636 0.4572)
			(stroke
				(width 0.1)
				(type default)
			)
			(layer "B.Fab")
		)
		(fp_line
			(start -0.8636 -0.406654)
			(end -1.1938 -0.406654)
			(stroke
				(width 0.1)
				(type default)
			)
			(layer "B.Fab")
		)
		(fp_line
			(start -0.8636 -0.4572)
			(end -0.8636 -0.406654)
			(stroke
				(width 0.1)
				(type default)
			)
			(layer "B.Fab")
		)
		(fp_line
			(start -1.1938 0.4064)
			(end -0.8636 0.4064)
			(stroke
				(width 0.1)
				(type default)
			)
			(layer "B.Fab")
		)
		(fp_line
			(start -1.1938 -0.406654)
			(end -1.1938 0.4064)
			(stroke
				(width 0.1)
				(type default)
			)
			(layer "B.Fab")
		)
		(pad "1" smd rect
			(at 0.7366 0 90)
			(size 0.7112 0.8128)
			(layers "B.Cu" "B.Mask" "B.Paste")
			(net "P0V9_CPU1_RT_2D")
		)
		(pad "2" smd rect
			(at -0.7366 0 90)
			(size 0.7112 0.8128)
			(layers "B.Cu" "B.Mask" "B.Paste")
			(net "P0V9_CPU1_RT2_2A_2D")
		)
	)
	(footprint ""
		(layer "B.Cu")
		(at 321.530726 -416.899344 90)
		(property "Reference" "C6543"
			(at 0 0 90)
			(layer "B.SilkS")
			(hide yes)
			(effects
				(font
					(size 1.27 1.27)
				)
				(justify mirror)
			)
		)
		(property "Value" ""
			(at 0 0 90)
			(layer "B.Fab")
			(effects
				(font
					(size 1.27 1.27)
				)
				(justify mirror)
			)
		)
		(duplicate_pad_numbers_are_jumpers no)
		(fp_line
			(start 0.299974 -0.150114)
			(end -0.299974 -0.150114)
			(stroke
				(width 0.1)
				(type default)
			)
			(layer "B.Fab")
		)
		(fp_line
			(start -0.299974 -0.150114)
			(end -0.299974 0.150114)
			(stroke
				(width 0.1)
				(type default)
			)
			(layer "B.Fab")
		)
		(fp_line
			(start 0.299974 0.150114)
			(end 0.299974 -0.150114)
			(stroke
				(width 0.1)
				(type default)
			)
			(layer "B.Fab")
		)
		(fp_line
			(start -0.299974 0.150114)
			(end 0.299974 0.150114)
			(stroke
				(width 0.1)
				(type default)
			)
			(layer "B.Fab")
		)
		(pad "1" smd rect
			(at 0.2667 0 270)
			(size 0.3048 0.381)
			(layers "B.Cu" "B.Mask" "B.Paste")
			(net "P5E_CPU0_P1_TX_BUF_C_DP<5>")
		)
		(pad "2" smd rect
			(at -0.2667 0 270)
			(size 0.3048 0.381)
			(layers "B.Cu" "B.Mask" "B.Paste")
			(net "P5E_CPU0_P1_TX_BUF_DP<5>")
		)
	)
	(footprint ""
		(layer "B.Cu")
		(at 256.432558 -328.744072)
		(property "Reference" "R1230"
			(at 0 0 0)
			(layer "B.SilkS")
			(hide yes)
			(effects
				(font
					(size 1.27 1.27)
				)
				(justify mirror)
			)
		)
		(property "Value" ""
			(at 0 0 0)
			(layer "B.Fab")
			(effects
				(font
					(size 1.27 1.27)
				)
				(justify mirror)
			)
		)
		(duplicate_pad_numbers_are_jumpers no)
		(fp_line
			(start -0.7874 -0.4064)
			(end -0.7874 0.4064)
			(stroke
				(width 0.1524)
				(type default)
			)
			(layer "B.SilkS")
		)
		(fp_line
			(start -0.7874 0.4064)
			(end 0.7874 0.4064)
			(stroke
				(width 0.1524)
				(type default)
			)
			(layer "B.SilkS")
		)
		(fp_line
			(start 0.7874 -0.4064)
			(end -0.7874 -0.4064)
			(stroke
				(width 0.1524)
				(type default)
			)
			(layer "B.SilkS")
		)
		(fp_line
			(start 0.7874 0.4064)
			(end 0.7874 -0.4064)
			(stroke
				(width 0.1524)
				(type default)
			)
			(layer "B.SilkS")
		)
		(fp_line
			(start -0.67945 -0.3048)
			(end -0.67945 0.3048)
			(stroke
				(width 0.1)
				(type default)
			)
			(layer "B.Fab")
		)
		(fp_line
			(start -0.67945 0.3048)
			(end -0.120396 0.3048)
			(stroke
				(width 0.1)
				(type default)
			)
			(layer "B.Fab")
		)
		(fp_line
			(start -0.12065 -0.3048)
			(end -0.67945 -0.3048)
			(stroke
				(width 0.1)
				(type default)
			)
			(layer "B.Fab")
		)
		(fp_line
			(start -0.12065 -0.2794)
			(end -0.12065 -0.3048)
			(stroke
				(width 0.1)
				(type default)
			)
			(layer "B.Fab")
		)
		(fp_line
			(start -0.120396 0.2794)
			(end 0.12065 0.2794)
			(stroke
				(width 0.1)
				(type default)
			)
			(layer "B.Fab")
		)
		(fp_line
			(start -0.120396 0.3048)
			(end -0.120396 0.2794)
			(stroke
				(width 0.1)
				(type default)
			)
			(layer "B.Fab")
		)
		(fp_line
			(start 0.12065 -0.305054)
			(end 0.12065 -0.2794)
			(stroke
				(width 0.1)
				(type default)
			)
			(layer "B.Fab")
		)
		(fp_line
			(start 0.12065 -0.2794)
			(end -0.12065 -0.2794)
			(stroke
				(width 0.1)
				(type default)
			)
			(layer "B.Fab")
		)
		(fp_line
			(start 0.12065 0.2794)
			(end 0.12065 0.3048)
			(stroke
				(width 0.1)
				(type default)
			)
			(layer "B.Fab")
		)
		(fp_line
			(start 0.12065 0.3048)
			(end 0.67945 0.3048)
			(stroke
				(width 0.1)
				(type default)
			)
			(layer "B.Fab")
		)
		(fp_line
			(start 0.67945 -0.305054)
			(end 0.12065 -0.305054)
			(stroke
				(width 0.1)
				(type default)
			)
			(layer "B.Fab")
		)
		(fp_line
			(start 0.67945 0.3048)
			(end 0.67945 -0.305054)
			(stroke
				(width 0.1)
				(type default)
			)
			(layer "B.Fab")
		)
		(pad "1" smd circle
			(at 0.40005 0 180)
			(size 0 0)
			(layers "B.Cu" "B.Mask" "B.Paste")
			(net "MAX11617_2_VREF")
		)
		(pad "2" smd circle
			(at -0.40005 0 180)
			(size 0 0)
			(layers "B.Cu" "B.Mask" "B.Paste")
			(net "MAX11617_2_VREF_R")
		)
	)
)
